# T6G (Grand Teton) — schematic netlist excerpt (pin names and nets, part order shuffled) for the footprints in the layout excerpt that follows; sources: Cadence DE-HDL packaged netlist, KiCad conversion of 04192023_DAF0TMB3IC0_F0TG_MB_C_brd_V02_OCP.brd

U33  SN74LVC1G07DBVR  IC  pkg SMLF  page 142
  NC  = NC
  A  = HP_LVC3_OCP_V3_2_P12V_R_PWRGD
  GND  = GND
  Y  = P12V_OCP_V3_2_PLD_R_PWRGD
  VCC  = P3V3_AUX

R1443  Q_RES  16.9K 1% CHIP  pkg 0402LF  page 259 : A = PWRGD_P12V_MEM_CPU0_EN ; B = GND

(kicad_pcb
	(version 20260206)
	(generator "pcbnew")
	(generator_version "10.0")
	(general
		(thickness 1.6)
		(legacy_teardrops no)
	)
	(paper "A4")
	(title_block
		(title "04192023_DAF0TMB3IC0_F0TG_MB_C_brd_V02_OCP.brd")
		(comment 1 "Grand Teton / footprints 4422-4423 of 8354")
	)
	(layers
		(0 "F.Cu" signal "TOP")
		(4 "In1.Cu" signal "GND")
		(6 "In2.Cu" signal "IN1")
		(8 "In3.Cu" signal "GND1")
		(10 "In4.Cu" signal "IN2")
		(12 "In5.Cu" signal "GND2")
		(14 "In6.Cu" signal "IN3")
		(16 "In7.Cu" signal "GND3")
		(18 "In8.Cu" signal "VCC")
		(20 "In9.Cu" signal "VCC1")
		(22 "In10.Cu" signal "GND4")
		(24 "In11.Cu" signal "IN4")
		(26 "In12.Cu" signal "GND5")
		(28 "In13.Cu" signal "IN5")
		(30 "In14.Cu" signal "GND6")
		(32 "In15.Cu" signal "IN6")
		(34 "In16.Cu" signal "GND7")
		(2 "B.Cu" signal "BOTTOM")
		(9 "F.Adhes" user "F.Adhesive")
		(11 "B.Adhes" user "B.Adhesive")
		(13 "F.Paste" user "Package Geometry/Pastemask Top")
		(15 "B.Paste" user "Package Geometry/Pastemask Bottom")
		(5 "F.SilkS" user "Ref Des/Silkscreen Top")
		(7 "B.SilkS" user "Ref Des/Silkscreen Bottom")
		(1 "F.Mask" user "Board Geometry/Soldermask Top")
		(3 "B.Mask" user "Board Geometry/Soldermask Bottom")
		(17 "Dwgs.User" user "User.Drawings")
		(19 "Cmts.User" user "User.Comments")
		(21 "Eco1.User" user "User.Eco1")
		(23 "Eco2.User" user "User.Eco2")
		(25 "Edge.Cuts" user "Board Geometry/Outline")
		(27 "Margin" user)
		(31 "F.CrtYd" user "Package Geometry/Place Bound Top")
		(29 "B.CrtYd" user "Package Geometry/Place Bound Bottom")
		(35 "F.Fab" user "Ref Des/Assembly Top")
		(33 "B.Fab" user "Ref Des/Assembly Bottom")
	)
	(footprint ""
		(layer "F.Cu")
		(at 95.885 -78.105)
		(property "Reference" "U33"
			(at -2.032 -2.377948 0)
			(unlocked yes)
			(layer "F.SilkS")
			(effects
				(font
					(size 0.7874 0.5842)
					(thickness 0.1524)
				)
				(justify left)
			)
		)
		(property "Value" ""
			(at 0 0 0)
			(layer "F.Fab")
			(effects
				(font
					(size 1.27 1.27)
				)
			)
		)
		(duplicate_pad_numbers_are_jumpers no)
		(fp_line
			(start -2.0574 -1.651)
			(end -0.381 -1.651)
			(stroke
				(width 0.1524)
				(type default)
			)
			(layer "F.SilkS")
		)
		(fp_line
			(start -2.0574 1.651)
			(end -2.0574 -1.651)
			(stroke
				(width 0.1524)
				(type default)
			)
			(layer "F.SilkS")
		)
		(fp_line
			(start -0.381 -1.651)
			(end 0 -1.016)
			(stroke
				(width 0.1524)
				(type default)
			)
			(layer "F.SilkS")
		)
		(fp_line
			(start 0 -1.016)
			(end 0.381 -1.651)
			(stroke
				(width 0.1524)
				(type default)
			)
			(layer "F.SilkS")
		)
		(fp_line
			(start 0.381 -1.651)
			(end 2.0574 -1.651)
			(stroke
				(width 0.1524)
				(type default)
			)
			(layer "F.SilkS")
		)
		(fp_line
			(start 2.0574 -1.651)
			(end 2.0574 1.651)
			(stroke
				(width 0.1524)
				(type default)
			)
			(layer "F.SilkS")
		)
		(fp_line
			(start 2.0574 1.651)
			(end -2.0574 1.651)
			(stroke
				(width 0.1524)
				(type default)
			)
			(layer "F.SilkS")
		)
		(fp_poly
			(pts
				(xy -2.71272 -0.719328) (xy -2.71272 -1.344168) (xy -2.159 -1.016)
			)
			(stroke
				(width 0)
				(type default)
			)
			(fill yes)
			(layer "F.SilkS")
		)
		(fp_line
			(start -1.599946 -1.199896)
			(end -0.899922 -1.199896)
			(stroke
				(width 0.1)
				(type default)
			)
			(layer "F.Fab")
		)
		(fp_line
			(start -1.599946 1.199896)
			(end -1.599946 -1.199896)
			(stroke
				(width 0.1)
				(type default)
			)
			(layer "F.Fab")
		)
		(fp_line
			(start -0.899922 -1.549908)
			(end 0.899922 -1.549908)
			(stroke
				(width 0.1)
				(type default)
			)
			(layer "F.Fab")
		)
		(fp_line
			(start -0.899922 -1.199896)
			(end -0.899922 -1.549908)
			(stroke
				(width 0.1)
				(type default)
			)
			(layer "F.Fab")
		)
		(fp_line
			(start -0.899922 1.199896)
			(end -1.599946 1.199896)
			(stroke
				(width 0.1)
				(type default)
			)
			(layer "F.Fab")
		)
		(fp_line
			(start -0.899922 1.549908)
			(end -0.899922 1.199896)
			(stroke
				(width 0.1)
				(type default)
			)
			(layer "F.Fab")
		)
		(fp_line
			(start 0.899922 -1.549908)
			(end 0.899922 -1.199896)
			(stroke
				(width 0.1)
				(type default)
			)
			(layer "F.Fab")
		)
		(fp_line
			(start 0.899922 -1.199896)
			(end 1.599946 -1.199896)
			(stroke
				(width 0.1)
				(type default)
			)
			(layer "F.Fab")
		)
		(fp_line
			(start 0.899922 1.199896)
			(end 0.899922 1.549908)
			(stroke
				(width 0.1)
				(type default)
			)
			(layer "F.Fab")
		)
		(fp_line
			(start 0.899922 1.549908)
			(end -0.899922 1.549908)
			(stroke
				(width 0.1)
				(type default)
			)
			(layer "F.Fab")
		)
		(fp_line
			(start 1.599946 -1.199896)
			(end 1.599946 1.199896)
			(stroke
				(width 0.1)
				(type default)
			)
			(layer "F.Fab")
		)
		(fp_line
			(start 1.599946 1.199896)
			(end 0.899922 1.199896)
			(stroke
				(width 0.1)
				(type default)
			)
			(layer "F.Fab")
		)
		(fp_poly
			(pts
				(xy -2.71272 -0.719328) (xy -2.71272 -1.344168) (xy -2.159 -1.016)
			)
			(stroke
				(width 0)
				(type default)
			)
			(fill yes)
			(layer "F.Fab")
		)
		(pad "1" smd rect
			(at -1.225042 -0.94996 270)
			(size 0.5588 1.3462)
			(layers "F.Cu" "F.Mask" "F.Paste")
			(net "Net_10853")
		)
		(pad "2" smd rect
			(at -1.225042 0 270)
			(size 0.5588 1.3462)
			(layers "F.Cu" "F.Mask" "F.Paste")
			(net "HP_LVC3_OCP_V3_2_P12V_R_PWRGD")
		)
		(pad "3" smd rect
			(at -1.225042 0.94996 270)
			(size 0.5588 1.3462)
			(layers "F.Cu" "F.Mask" "F.Paste")
			(net "GND")
		)
		(pad "4" smd rect
			(at 1.225042 0.94996 270)
			(size 0.5588 1.3462)
			(layers "F.Cu" "F.Mask" "F.Paste")
			(net "P12V_OCP_V3_2_PLD_R_PWRGD")
		)
		(pad "5" smd rect
			(at 1.225042 -0.94996 270)
			(size 0.5588 1.3462)
			(layers "F.Cu" "F.Mask" "F.Paste")
			(net "P3V3_AUX")
		)
	)
	(footprint ""
		(layer "F.Cu")
		(at 102.154736 -127.787654 90)
		(property "Reference" "R1443"
			(at 0 0 90)
			(layer "F.SilkS")
			(hide yes)
			(effects
				(font
					(size 1.27 1.27)
				)
			)
		)
		(property "Value" ""
			(at 0 0 90)
			(layer "F.Fab")
			(effects
				(font
					(size 1.27 1.27)
				)
			)
		)
		(duplicate_pad_numbers_are_jumpers no)
		(fp_line
			(start 0.7874 -0.4064)
			(end 0.7874 0.4064)
			(stroke
				(width 0.1524)
				(type default)
			)
			(layer "F.SilkS")
		)
		(fp_line
			(start -0.7874 -0.4064)
			(end 0.7874 -0.4064)
			(stroke
				(width 0.1524)
				(type default)
			)
			(layer "F.SilkS")
		)
		(fp_line
			(start 0.7874 0.4064)
			(end -0.7874 0.4064)
			(stroke
				(width 0.1524)
				(type default)
			)
			(layer "F.SilkS")
		)
		(fp_line
			(start -0.7874 0.4064)
			(end -0.7874 -0.4064)
			(stroke
				(width 0.1524)
				(type default)
			)
			(layer "F.SilkS")
		)
		(fp_line
			(start -0.12065 -0.305054)
			(end -0.12065 -0.2794)
			(stroke
				(width 0.1)
				(type default)
			)
			(layer "F.Fab")
		)
		(fp_line
			(start -0.67945 -0.305054)
			(end -0.12065 -0.305054)
			(stroke
				(width 0.1)
				(type default)
			)
			(layer "F.Fab")
		)
		(fp_line
			(start 0.67945 -0.3048)
			(end 0.67945 0.3048)
			(stroke
				(width 0.1)
				(type default)
			)
			(layer "F.Fab")
		)
		(fp_line
			(start 0.12065 -0.3048)
			(end 0.67945 -0.3048)
			(stroke
				(width 0.1)
				(type default)
			)
			(layer "F.Fab")
		)
		(fp_line
			(start 0.12065 -0.2794)
			(end 0.12065 -0.3048)
			(stroke
				(width 0.1)
				(type default)
			)
			(layer "F.Fab")
		)
		(fp_line
			(start -0.12065 -0.2794)
			(end 0.12065 -0.2794)
			(stroke
				(width 0.1)
				(type default)
			)
			(layer "F.Fab")
		)
		(fp_line
			(start 0.120396 0.2794)
			(end -0.12065 0.2794)
			(stroke
				(width 0.1)
				(type default)
			)
			(layer "F.Fab")
		)
		(fp_line
			(start -0.12065 0.2794)
			(end -0.12065 0.3048)
			(stroke
				(width 0.1)
				(type default)
			)
			(layer "F.Fab")
		)
		(fp_line
			(start 0.67945 0.3048)
			(end 0.120396 0.3048)
			(stroke
				(width 0.1)
				(type default)
			)
			(layer "F.Fab")
		)
		(fp_line
			(start 0.120396 0.3048)
			(end 0.120396 0.2794)
			(stroke
				(width 0.1)
				(type default)
			)
			(layer "F.Fab")
		)
		(fp_line
			(start -0.12065 0.3048)
			(end -0.67945 0.3048)
			(stroke
				(width 0.1)
				(type default)
			)
			(layer "F.Fab")
		)
		(fp_line
			(start -0.67945 0.3048)
			(end -0.67945 -0.305054)
			(stroke
				(width 0.1)
				(type default)
			)
			(layer "F.Fab")
		)
		(pad "1" smd circle
			(at -0.40005 0 90)
			(size 0 0)
			(layers "F.Cu" "F.Mask" "F.Paste")
			(net "PWRGD_P12V_MEM_CPU0_EN")
		)
		(pad "2" smd circle
			(at 0.40005 0 90)
			(size 0 0)
			(layers "F.Cu" "F.Mask" "F.Paste")
			(net "GND")
		)
	)
)
